#ISCELL
  cls sheet_a1 *
  *
#ISCELL
  cls gnd_sg *
  page12_i120
#CELL
  discrete diode_4_v1 *
  page12_i179
#CELL
  passive resistor *
  page12_i197
#CELL
  stdlogic 74hct2g125dp_tssop8 *
  page12_i204
#CELL
  passive resistor *
  page12_i206
#CELL
  passive capacitor *
  page12_i207
#ISCELL
  cls offpage_in *
  page12_i208
#CELL
  passive resistor *
  page12_i209
#ISCELL
  cls vcc *
  page12_i210
#ISCELL
  cls gnd_sg *
  page12_i211
#ISCELL
  cls offpage_out *
  page12_i212
#CELL
  stdlogic 74hct2g125dp_tssop8 *
  page12_i226
#ISCELL
  cls offpage_out *
  page12_i227
#CELL
  passive resistor *
  page12_i228
#CELL
  passive resistor *
  page12_i229
#ISCELL
  cls vcc *
  page12_i230
#CELL
  passive capacitor *
  page12_i231
#ISCELL
  cls gnd_sg *
  page12_i232
#CELL
  passive resistor *
  page12_i233
#CELL
  passive resistor *
  page12_i234
#ISCELL
  cls vcc *
  page12_i236
#CELL
  passive resistor *
  page12_i237
#ISCELL
  cls offpage_in *
  page12_i239
#ISCELL
  cls offpage_in *
  page12_i240
#ISCELL
  cls offpage_in *
  page12_i241
#CELL
  stdlogic 74hct2g125dp_tssop8 *
  page12_i255
#ISCELL
  cls offpage_out *
  page12_i256
#CELL
  passive resistor *
  page12_i257
#CELL
  passive resistor *
  page12_i258
#ISCELL
  cls vcc *
  page12_i259
#CELL
  passive resistor *
  page12_i261
#CELL
  passive resistor *
  page12_i262
#ISCELL
  cls vcc *
  page12_i264
#CELL
  passive resistor *
  page12_i265
#ISCELL
  cls offpage_in *
  page12_i267
#ISCELL
  cls offpage_in *
  page12_i268
#ISCELL
  cls offpage_in *
  page12_i269
#ISCELL
  cls gnd_sg *
  page12_i271
#CELL
  passive capacitor *
  page12_i272
#CELL
  stdlogic 74hct2g125dp_tssop8 *
  page12_i273
#ISCELL
  cls offpage_out *
  page12_i274
#CELL
  passive resistor *
  page12_i275
#CELL
  passive resistor *
  page12_i276
#ISCELL
  cls vcc *
  page12_i277
#ISCELL
  cls gnd_sg *
  page12_i279
#CELL
  passive resistor *
  page12_i280
#CELL
  passive resistor *
  page12_i281
#ISCELL
  cls vcc *
  page12_i282
#CELL
  passive resistor *
  page12_i284
#ISCELL
  cls offpage_in *
  page12_i286
#ISCELL
  cls offpage_in *
  page12_i287
#ISCELL
  cls offpage_in *
  page12_i288
#CELL
  passive capacitor *
  page12_i289
#CELL
  connector conn_jack_1p_gh4_s_th *
  page12_i290
#ISCELL
  cls gnd_sg *
  page12_i291
#ISCELL
  cls gnd_sg *
  page12_i292
#ISCELL
  cls gnd_sg *
  page12_i293
#CELL
  connector conn_jack_1p_gh4_s_th *
  page12_i294
#ISCELL
  cls gnd_sg *
  page12_i295
#ISCELL
  cls gnd_sg *
  page12_i296
#CELL
  connector conn_jack_1p_gh4_s_th *
  page12_i297
#ISCELL
  cls gnd_sg *
  page12_i298
#ISCELL
  cls gnd_sg *
  page12_i299
#CELL
  connector conn_jack_1p_gh4_s_th *
  page12_i300
#ISCELL
  cls gnd_sg *
  page12_i317
#CELL
  passive capacitor *
  page12_i318
#CELL
  passive resistor *
  page12_i319
#CELL
  passive resistor *
  page12_i320
#CELL
  passive capacitor *
  page12_i321
#CELL
  passive resistor *
  page12_i322
#CELL
  passive resistor *
  page12_i323
#ISCELL
  cls gnd_sg *
  page12_i324
#ISCELL
  cls gnd_sg *
  page12_i325
#CELL
  passive resistor *
  page12_i326
#CELL
  passive resistor *
  page12_i327
#CELL
  passive capacitor *
  page12_i328
#ISCELL
  cls gnd_sg *
  page12_i329
#CELL
  passive resistor *
  page12_i330
#CELL
  passive resistor *
  page12_i331
#CELL
  passive capacitor *
  page12_i332
#ISCELL
  cls gnd_sg *
  page12_i41
#CELL
  discrete diode_4_v1 *
  page12_i42
#ISCELL
  cls gnd_sg *
  page12_i55
#ISCELL
  cls offpage_in *
  page12_i61
#CELL
  passive resistor *
  page12_i63
#ISCELL
  cls offpage_in *
  page12_i79
#CELL
  passive resistor *
  page12_i88
#ISCELL
  cls vcc *
  page12_i89
